(kicad_pcb
	(version 20260206)
	(generator "pcbnew")
	(generator_version "10.0")
	(general
		(thickness 1.6)
		(legacy_teardrops no)
	)
	(paper "A4")
	(title_block
		(title "01162023_DA0F0TEBIF0_F0T_Expander_BD_F_brd_V02_OCP.brd")
		(comment 1 "Grand Teton / footprints 3371-3377 of 9728")
	)
	(layers
		(0 "F.Cu" signal "TOP")
		(4 "In1.Cu" signal "GND")
		(6 "In2.Cu" signal "VCC")
		(8 "In3.Cu" signal "VCC1")
		(10 "In4.Cu" signal "GND1")
		(12 "In5.Cu" signal "IN1")
		(14 "In6.Cu" signal "GND2")
		(16 "In7.Cu" signal "IN2")
		(18 "In8.Cu" signal "GND3")
		(20 "In9.Cu" signal "IN3")
		(22 "In10.Cu" signal "GND4")
		(24 "In11.Cu" signal "IN4")
		(26 "In12.Cu" signal "GND5")
		(28 "In13.Cu" signal "IN5")
		(30 "In14.Cu" signal "GND6")
		(32 "In15.Cu" signal "IN6")
		(34 "In16.Cu" signal "GND7")
		(2 "B.Cu" signal "BOTTOM")
		(9 "F.Adhes" user "F.Adhesive")
		(11 "B.Adhes" user "B.Adhesive")
		(13 "F.Paste" user "Package Geometry/Pastemask Top")
		(15 "B.Paste" user "Package Geometry/Pastemask Bottom")
		(5 "F.SilkS" user "Ref Des/Silkscreen Top")
		(7 "B.SilkS" user "Ref Des/Silkscreen Bottom")
		(1 "F.Mask" user "Board Geometry/Soldermask Top")
		(3 "B.Mask" user "Board Geometry/Soldermask Bottom")
		(17 "Dwgs.User" user "User.Drawings")
		(19 "Cmts.User" user "User.Comments")
		(21 "Eco1.User" user "User.Eco1")
		(23 "Eco2.User" user "User.Eco2")
		(25 "Edge.Cuts" user "Board Geometry/Outline")
		(27 "Margin" user)
		(31 "F.CrtYd" user "Package Geometry/Place Bound Top")
		(29 "B.CrtYd" user "Package Geometry/Place Bound Bottom")
		(35 "F.Fab" user "Ref Des/Assembly Top")
		(33 "B.Fab" user "Ref Des/Assembly Bottom")
	)
	(footprint ""
		(layer "F.Cu")
		(at 263.95426 -48.21809)
		(property "Reference" "PD70"
			(at -3.35026 2.24536 0)
			(unlocked yes)
			(layer "F.SilkS")
			(effects
				(font
					(size 0.7874 0.5842)
					(thickness 0.1524)
				)
				(justify left)
			)
		)
		(property "Value" ""
			(at 0 0 0)
			(layer "F.Fab")
			(effects
				(font
					(size 1.27 1.27)
				)
			)
		)
		(duplicate_pad_numbers_are_jumpers no)
		(fp_line
			(start -3.400044 -1.459992)
			(end 4.107942 -1.459992)
			(stroke
				(width 0.1524)
				(type default)
			)
			(layer "F.SilkS")
		)
		(fp_line
			(start -3.400044 1.459992)
			(end -3.400044 -1.459992)
			(stroke
				(width 0.1524)
				(type default)
			)
			(layer "F.SilkS")
		)
		(fp_line
			(start 4.107942 -1.459992)
			(end 4.107942 1.459992)
			(stroke
				(width 0.1524)
				(type default)
			)
			(layer "F.SilkS")
		)
		(fp_line
			(start 4.107942 1.459992)
			(end -3.400044 1.459992)
			(stroke
				(width 0.1524)
				(type default)
			)
			(layer "F.SilkS")
		)
		(fp_poly
			(pts
				(xy 4.107942 -1.459992) (xy 4.107942 1.459992) (xy 3.308096 1.459992) (xy 3.308096 -1.459992)
			)
			(stroke
				(width 0)
				(type default)
			)
			(fill yes)
			(layer "F.SilkS")
		)
		(fp_line
			(start -2.29997 -1.459992)
			(end 2.29997 -1.459992)
			(stroke
				(width 0.1)
				(type default)
			)
			(layer "F.Fab")
		)
		(fp_line
			(start -2.29997 1.459992)
			(end -2.29997 -1.459992)
			(stroke
				(width 0.1)
				(type default)
			)
			(layer "F.Fab")
		)
		(fp_line
			(start 2.29997 -1.459992)
			(end 2.29997 1.459992)
			(stroke
				(width 0.1)
				(type default)
			)
			(layer "F.Fab")
		)
		(fp_line
			(start 2.29997 1.459992)
			(end -2.29997 1.459992)
			(stroke
				(width 0.1)
				(type default)
			)
			(layer "F.Fab")
		)
		(fp_text user "+"
			(at -4.7752 -0.12065 0)
			(unlocked yes)
			(layer "F.SilkS")
			(effects
				(font
					(size 1.905 1.4224)
					(thickness 0.1524)
				)
				(justify left)
			)
		)
		(fp_text user "-"
			(at 5.4102 0.29845 180)
			(unlocked yes)
			(layer "F.SilkS")
			(effects
				(font
					(size 1.905 1.4224)
					(thickness 0.1524)
				)
				(justify left)
			)
		)
		(fp_text user "+"
			(at -4.7752 -0.12065 0)
			(unlocked yes)
			(layer "F.Fab")
			(effects
				(font
					(size 1.905 1.4224)
					(thickness 0.1524)
				)
				(justify left)
			)
		)
		(fp_text user "-"
			(at 5.4102 0.29845 180)
			(unlocked yes)
			(layer "F.Fab")
			(effects
				(font
					(size 1.905 1.4224)
					(thickness 0.1524)
				)
				(justify left)
			)
		)
		(pad "A" smd rect
			(at -1.999996 0 90)
			(size 1.7018 2.5146)
			(layers "F.Cu" "F.Mask" "F.Paste")
			(net "GND")
		)
		(pad "C" smd rect
			(at 1.999996 0 90)
			(size 1.7018 2.5146)
			(layers "F.Cu" "F.Mask" "F.Paste")
			(net "P3V3_SSD9")
		)
	)
	(footprint ""
		(layer "F.Cu")
		(at 338.074 -174.117)
		(property "Reference" "R4767"
			(at 0 0 0)
			(layer "F.SilkS")
			(hide yes)
			(effects
				(font
					(size 1.27 1.27)
				)
			)
		)
		(property "Value" ""
			(at 0 0 0)
			(layer "F.Fab")
			(effects
				(font
					(size 1.27 1.27)
				)
			)
		)
		(duplicate_pad_numbers_are_jumpers no)
		(fp_line
			(start -0.7874 -0.4064)
			(end 0.7874 -0.4064)
			(stroke
				(width 0.1524)
				(type default)
			)
			(layer "F.SilkS")
		)
		(fp_line
			(start -0.7874 0.4064)
			(end -0.7874 -0.4064)
			(stroke
				(width 0.1524)
				(type default)
			)
			(layer "F.SilkS")
		)
		(fp_line
			(start 0.7874 -0.4064)
			(end 0.7874 0.4064)
			(stroke
				(width 0.1524)
				(type default)
			)
			(layer "F.SilkS")
		)
		(fp_line
			(start 0.7874 0.4064)
			(end -0.7874 0.4064)
			(stroke
				(width 0.1524)
				(type default)
			)
			(layer "F.SilkS")
		)
		(fp_line
			(start -0.67945 -0.305054)
			(end -0.12065 -0.305054)
			(stroke
				(width 0.1)
				(type default)
			)
			(layer "F.Fab")
		)
		(fp_line
			(start -0.67945 0.3048)
			(end -0.67945 -0.305054)
			(stroke
				(width 0.1)
				(type default)
			)
			(layer "F.Fab")
		)
		(fp_line
			(start -0.12065 -0.305054)
			(end -0.12065 -0.2794)
			(stroke
				(width 0.1)
				(type default)
			)
			(layer "F.Fab")
		)
		(fp_line
			(start -0.12065 -0.2794)
			(end 0.12065 -0.2794)
			(stroke
				(width 0.1)
				(type default)
			)
			(layer "F.Fab")
		)
		(fp_line
			(start -0.12065 0.2794)
			(end -0.12065 0.3048)
			(stroke
				(width 0.1)
				(type default)
			)
			(layer "F.Fab")
		)
		(fp_line
			(start -0.12065 0.3048)
			(end -0.67945 0.3048)
			(stroke
				(width 0.1)
				(type default)
			)
			(layer "F.Fab")
		)
		(fp_line
			(start 0.120396 0.2794)
			(end -0.12065 0.2794)
			(stroke
				(width 0.1)
				(type default)
			)
			(layer "F.Fab")
		)
		(fp_line
			(start 0.120396 0.3048)
			(end 0.120396 0.2794)
			(stroke
				(width 0.1)
				(type default)
			)
			(layer "F.Fab")
		)
		(fp_line
			(start 0.12065 -0.3048)
			(end 0.67945 -0.3048)
			(stroke
				(width 0.1)
				(type default)
			)
			(layer "F.Fab")
		)
		(fp_line
			(start 0.12065 -0.2794)
			(end 0.12065 -0.3048)
			(stroke
				(width 0.1)
				(type default)
			)
			(layer "F.Fab")
		)
		(fp_line
			(start 0.67945 -0.3048)
			(end 0.67945 0.3048)
			(stroke
				(width 0.1)
				(type default)
			)
			(layer "F.Fab")
		)
		(fp_line
			(start 0.67945 0.3048)
			(end 0.120396 0.3048)
			(stroke
				(width 0.1)
				(type default)
			)
			(layer "F.Fab")
		)
		(pad "1" smd circle
			(at -0.40005 0)
			(size 0 0)
			(layers "F.Cu" "F.Mask" "F.Paste")
			(net "PEX2_PCA9555_1_INT_N")
		)
		(pad "2" smd circle
			(at 0.40005 0)
			(size 0 0)
			(layers "F.Cu" "F.Mask" "F.Paste")
			(net "P1V8_PEX")
		)
	)
	(footprint ""
		(layer "F.Cu")
		(at 83.034124 -4.014724)
		(property "Reference" "R5807"
			(at 0 0 0)
			(layer "F.SilkS")
			(hide yes)
			(effects
				(font
					(size 1.27 1.27)
				)
			)
		)
		(property "Value" ""
			(at 0 0 0)
			(layer "F.Fab")
			(effects
				(font
					(size 1.27 1.27)
				)
			)
		)
		(duplicate_pad_numbers_are_jumpers no)
		(fp_line
			(start -0.7874 -0.4064)
			(end 0.7874 -0.4064)
			(stroke
				(width 0.1524)
				(type default)
			)
			(layer "F.SilkS")
		)
		(fp_line
			(start -0.7874 0.4064)
			(end -0.7874 -0.4064)
			(stroke
				(width 0.1524)
				(type default)
			)
			(layer "F.SilkS")
		)
		(fp_line
			(start 0.7874 -0.4064)
			(end 0.7874 0.4064)
			(stroke
				(width 0.1524)
				(type default)
			)
			(layer "F.SilkS")
		)
		(fp_line
			(start 0.7874 0.4064)
			(end -0.7874 0.4064)
			(stroke
				(width 0.1524)
				(type default)
			)
			(layer "F.SilkS")
		)
		(fp_line
			(start -0.67945 -0.305054)
			(end -0.12065 -0.305054)
			(stroke
				(width 0.1)
				(type default)
			)
			(layer "F.Fab")
		)
		(fp_line
			(start -0.67945 0.3048)
			(end -0.67945 -0.305054)
			(stroke
				(width 0.1)
				(type default)
			)
			(layer "F.Fab")
		)
		(fp_line
			(start -0.12065 -0.305054)
			(end -0.12065 -0.2794)
			(stroke
				(width 0.1)
				(type default)
			)
			(layer "F.Fab")
		)
		(fp_line
			(start -0.12065 -0.2794)
			(end 0.12065 -0.2794)
			(stroke
				(width 0.1)
				(type default)
			)
			(layer "F.Fab")
		)
		(fp_line
			(start -0.12065 0.2794)
			(end -0.12065 0.3048)
			(stroke
				(width 0.1)
				(type default)
			)
			(layer "F.Fab")
		)
		(fp_line
			(start -0.12065 0.3048)
			(end -0.67945 0.3048)
			(stroke
				(width 0.1)
				(type default)
			)
			(layer "F.Fab")
		)
		(fp_line
			(start 0.120396 0.2794)
			(end -0.12065 0.2794)
			(stroke
				(width 0.1)
				(type default)
			)
			(layer "F.Fab")
		)
		(fp_line
			(start 0.120396 0.3048)
			(end 0.120396 0.2794)
			(stroke
				(width 0.1)
				(type default)
			)
			(layer "F.Fab")
		)
		(fp_line
			(start 0.12065 -0.3048)
			(end 0.67945 -0.3048)
			(stroke
				(width 0.1)
				(type default)
			)
			(layer "F.Fab")
		)
		(fp_line
			(start 0.12065 -0.2794)
			(end 0.12065 -0.3048)
			(stroke
				(width 0.1)
				(type default)
			)
			(layer "F.Fab")
		)
		(fp_line
			(start 0.67945 -0.3048)
			(end 0.67945 0.3048)
			(stroke
				(width 0.1)
				(type default)
			)
			(layer "F.Fab")
		)
		(fp_line
			(start 0.67945 0.3048)
			(end 0.120396 0.3048)
			(stroke
				(width 0.1)
				(type default)
			)
			(layer "F.Fab")
		)
		(pad "1" smd circle
			(at -0.40005 0)
			(size 0 0)
			(layers "F.Cu" "F.Mask" "F.Paste")
			(net "LM75_2_A2")
		)
		(pad "2" smd circle
			(at 0.40005 0)
			(size 0 0)
			(layers "F.Cu" "F.Mask" "F.Paste")
			(net "P3V3_AUX")
		)
	)
	(footprint ""
		(layer "F.Cu")
		(at 237.147354 -36.686998 90)
		(property "Reference" "C3675"
			(at 0 0 90)
			(layer "F.SilkS")
			(hide yes)
			(effects
				(font
					(size 1.27 1.27)
				)
			)
		)
		(property "Value" ""
			(at 0 0 90)
			(layer "F.Fab")
			(effects
				(font
					(size 1.27 1.27)
				)
			)
		)
		(duplicate_pad_numbers_are_jumpers no)
		(fp_line
			(start 0.7874 -0.4064)
			(end 0.7874 0.4064)
			(stroke
				(width 0.1524)
				(type default)
			)
			(layer "F.SilkS")
		)
		(fp_line
			(start -0.7874 -0.4064)
			(end 0.7874 -0.4064)
			(stroke
				(width 0.1524)
				(type default)
			)
			(layer "F.SilkS")
		)
		(fp_line
			(start 0.7874 0.4064)
			(end -0.7874 0.4064)
			(stroke
				(width 0.1524)
				(type default)
			)
			(layer "F.SilkS")
		)
		(fp_line
			(start -0.7874 0.4064)
			(end -0.7874 -0.4064)
			(stroke
				(width 0.1524)
				(type default)
			)
			(layer "F.SilkS")
		)
		(fp_line
			(start -0.12065 -0.305054)
			(end -0.12065 -0.2794)
			(stroke
				(width 0.1)
				(type default)
			)
			(layer "F.Fab")
		)
		(fp_line
			(start -0.67945 -0.305054)
			(end -0.12065 -0.305054)
			(stroke
				(width 0.1)
				(type default)
			)
			(layer "F.Fab")
		)
		(fp_line
			(start 0.67945 -0.3048)
			(end 0.67945 0.3048)
			(stroke
				(width 0.1)
				(type default)
			)
			(layer "F.Fab")
		)
		(fp_line
			(start 0.12065 -0.3048)
			(end 0.67945 -0.3048)
			(stroke
				(width 0.1)
				(type default)
			)
			(layer "F.Fab")
		)
		(fp_line
			(start 0.12065 -0.2794)
			(end 0.12065 -0.3048)
			(stroke
				(width 0.1)
				(type default)
			)
			(layer "F.Fab")
		)
		(fp_line
			(start -0.12065 -0.2794)
			(end 0.12065 -0.2794)
			(stroke
				(width 0.1)
				(type default)
			)
			(layer "F.Fab")
		)
		(fp_line
			(start 0.120396 0.2794)
			(end -0.12065 0.2794)
			(stroke
				(width 0.1)
				(type default)
			)
			(layer "F.Fab")
		)
		(fp_line
			(start -0.12065 0.2794)
			(end -0.12065 0.3048)
			(stroke
				(width 0.1)
				(type default)
			)
			(layer "F.Fab")
		)
		(fp_line
			(start 0.67945 0.3048)
			(end 0.120396 0.3048)
			(stroke
				(width 0.1)
				(type default)
			)
			(layer "F.Fab")
		)
		(fp_line
			(start 0.120396 0.3048)
			(end 0.120396 0.2794)
			(stroke
				(width 0.1)
				(type default)
			)
			(layer "F.Fab")
		)
		(fp_line
			(start -0.12065 0.3048)
			(end -0.67945 0.3048)
			(stroke
				(width 0.1)
				(type default)
			)
			(layer "F.Fab")
		)
		(fp_line
			(start -0.67945 0.3048)
			(end -0.67945 -0.305054)
			(stroke
				(width 0.1)
				(type default)
			)
			(layer "F.Fab")
		)
		(pad "1" smd circle
			(at -0.40005 0 90)
			(size 0 0)
			(layers "F.Cu" "F.Mask" "F.Paste")
			(net "P3V3_AUX")
		)
		(pad "2" smd circle
			(at 0.40005 0 90)
			(size 0 0)
			(layers "F.Cu" "F.Mask" "F.Paste")
			(net "GND")
		)
	)
	(footprint ""
		(layer "F.Cu")
		(at 98.975672 -120.493028)
		(property "Reference" "R4476"
			(at 0 0 0)
			(layer "F.SilkS")
			(hide yes)
			(effects
				(font
					(size 1.27 1.27)
				)
			)
		)
		(property "Value" ""
			(at 0 0 0)
			(layer "F.Fab")
			(effects
				(font
					(size 1.27 1.27)
				)
			)
		)
		(duplicate_pad_numbers_are_jumpers no)
		(fp_line
			(start -0.7874 -0.4064)
			(end 0.7874 -0.4064)
			(stroke
				(width 0.1524)
				(type default)
			)
			(layer "F.SilkS")
		)
		(fp_line
			(start -0.7874 0.4064)
			(end -0.7874 -0.4064)
			(stroke
				(width 0.1524)
				(type default)
			)
			(layer "F.SilkS")
		)
		(fp_line
			(start 0.7874 -0.4064)
			(end 0.7874 0.4064)
			(stroke
				(width 0.1524)
				(type default)
			)
			(layer "F.SilkS")
		)
		(fp_line
			(start 0.7874 0.4064)
			(end -0.7874 0.4064)
			(stroke
				(width 0.1524)
				(type default)
			)
			(layer "F.SilkS")
		)
		(fp_line
			(start -0.67945 -0.305054)
			(end -0.12065 -0.305054)
			(stroke
				(width 0.1)
				(type default)
			)
			(layer "F.Fab")
		)
		(fp_line
			(start -0.67945 0.3048)
			(end -0.67945 -0.305054)
			(stroke
				(width 0.1)
				(type default)
			)
			(layer "F.Fab")
		)
		(fp_line
			(start -0.12065 -0.305054)
			(end -0.12065 -0.2794)
			(stroke
				(width 0.1)
				(type default)
			)
			(layer "F.Fab")
		)
		(fp_line
			(start -0.12065 -0.2794)
			(end 0.12065 -0.2794)
			(stroke
				(width 0.1)
				(type default)
			)
			(layer "F.Fab")
		)
		(fp_line
			(start -0.12065 0.2794)
			(end -0.12065 0.3048)
			(stroke
				(width 0.1)
				(type default)
			)
			(layer "F.Fab")
		)
		(fp_line
			(start -0.12065 0.3048)
			(end -0.67945 0.3048)
			(stroke
				(width 0.1)
				(type default)
			)
			(layer "F.Fab")
		)
		(fp_line
			(start 0.120396 0.2794)
			(end -0.12065 0.2794)
			(stroke
				(width 0.1)
				(type default)
			)
			(layer "F.Fab")
		)
		(fp_line
			(start 0.120396 0.3048)
			(end 0.120396 0.2794)
			(stroke
				(width 0.1)
				(type default)
			)
			(layer "F.Fab")
		)
		(fp_line
			(start 0.12065 -0.3048)
			(end 0.67945 -0.3048)
			(stroke
				(width 0.1)
				(type default)
			)
			(layer "F.Fab")
		)
		(fp_line
			(start 0.12065 -0.2794)
			(end 0.12065 -0.3048)
			(stroke
				(width 0.1)
				(type default)
			)
			(layer "F.Fab")
		)
		(fp_line
			(start 0.67945 -0.3048)
			(end 0.67945 0.3048)
			(stroke
				(width 0.1)
				(type default)
			)
			(layer "F.Fab")
		)
		(fp_line
			(start 0.67945 0.3048)
			(end 0.120396 0.3048)
			(stroke
				(width 0.1)
				(type default)
			)
			(layer "F.Fab")
		)
		(pad "1" smd circle
			(at -0.40005 0)
			(size 0 0)
			(layers "F.Cu" "F.Mask" "F.Paste")
			(net "PWRGD_P3V3_NIC1")
		)
		(pad "2" smd circle
			(at 0.40005 0)
			(size 0 0)
			(layers "F.Cu" "F.Mask" "F.Paste")
			(net "PWRGD_P3V3_NIC1_R")
		)
	)
	(footprint ""
		(layer "F.Cu")
		(at 162.5346 -30.94609 180)
		(property "Reference" "C288"
			(at 0 0 180)
			(layer "F.SilkS")
			(hide yes)
			(effects
				(font
					(size 1.27 1.27)
				)
			)
		)
		(property "Value" ""
			(at 0 0 180)
			(layer "F.Fab")
			(effects
				(font
					(size 1.27 1.27)
				)
			)
		)
		(duplicate_pad_numbers_are_jumpers no)
		(fp_line
			(start 0.299974 0.150114)
			(end -0.299974 0.150114)
			(stroke
				(width 0.1)
				(type default)
			)
			(layer "F.Fab")
		)
		(fp_line
			(start 0.299974 -0.150114)
			(end 0.299974 0.150114)
			(stroke
				(width 0.1)
				(type default)
			)
			(layer "F.Fab")
		)
		(fp_line
			(start -0.299974 0.150114)
			(end -0.299974 -0.150114)
			(stroke
				(width 0.1)
				(type default)
			)
			(layer "F.Fab")
		)
		(fp_line
			(start -0.299974 -0.150114)
			(end 0.299974 -0.150114)
			(stroke
				(width 0.1)
				(type default)
			)
			(layer "F.Fab")
		)
		(pad "1" smd rect
			(at -0.2667 0 180)
			(size 0.3048 0.381)
			(layers "F.Cu" "F.Mask" "F.Paste")
			(net "P5E_PEX1_STN2_TX_DP<41>")
		)
		(pad "2" smd rect
			(at 0.2667 0 180)
			(size 0.3048 0.381)
			(layers "F.Cu" "F.Mask" "F.Paste")
			(net "P5E_PEX1_STN2_TX_C_DP<41>")
		)
	)
	(footprint ""
		(layer "F.Cu")
		(at 311.326022 -37.929566 90)
		(property "Reference" "R5582"
			(at 0 0 90)
			(layer "F.SilkS")
			(hide yes)
			(effects
				(font
					(size 1.27 1.27)
				)
			)
		)
		(property "Value" ""
			(at 0 0 90)
			(layer "F.Fab")
			(effects
				(font
					(size 1.27 1.27)
				)
			)
		)
		(duplicate_pad_numbers_are_jumpers no)
		(fp_line
			(start 0.7874 -0.4064)
			(end 0.7874 0.4064)
			(stroke
				(width 0.1524)
				(type default)
			)
			(layer "F.SilkS")
		)
		(fp_line
			(start -0.7874 -0.4064)
			(end 0.7874 -0.4064)
			(stroke
				(width 0.1524)
				(type default)
			)
			(layer "F.SilkS")
		)
		(fp_line
			(start 0.7874 0.4064)
			(end -0.7874 0.4064)
			(stroke
				(width 0.1524)
				(type default)
			)
			(layer "F.SilkS")
		)
		(fp_line
			(start -0.7874 0.4064)
			(end -0.7874 -0.4064)
			(stroke
				(width 0.1524)
				(type default)
			)
			(layer "F.SilkS")
		)
		(fp_line
			(start -0.12065 -0.305054)
			(end -0.12065 -0.2794)
			(stroke
				(width 0.1)
				(type default)
			)
			(layer "F.Fab")
		)
		(fp_line
			(start -0.67945 -0.305054)
			(end -0.12065 -0.305054)
			(stroke
				(width 0.1)
				(type default)
			)
			(layer "F.Fab")
		)
		(fp_line
			(start 0.67945 -0.3048)
			(end 0.67945 0.3048)
			(stroke
				(width 0.1)
				(type default)
			)
			(layer "F.Fab")
		)
		(fp_line
			(start 0.12065 -0.3048)
			(end 0.67945 -0.3048)
			(stroke
				(width 0.1)
				(type default)
			)
			(layer "F.Fab")
		)
		(fp_line
			(start 0.12065 -0.2794)
			(end 0.12065 -0.3048)
			(stroke
				(width 0.1)
				(type default)
			)
			(layer "F.Fab")
		)
		(fp_line
			(start -0.12065 -0.2794)
			(end 0.12065 -0.2794)
			(stroke
				(width 0.1)
				(type default)
			)
			(layer "F.Fab")
		)
		(fp_line
			(start 0.120396 0.2794)
			(end -0.12065 0.2794)
			(stroke
				(width 0.1)
				(type default)
			)
			(layer "F.Fab")
		)
		(fp_line
			(start -0.12065 0.2794)
			(end -0.12065 0.3048)
			(stroke
				(width 0.1)
				(type default)
			)
			(layer "F.Fab")
		)
		(fp_line
			(start 0.67945 0.3048)
			(end 0.120396 0.3048)
			(stroke
				(width 0.1)
				(type default)
			)
			(layer "F.Fab")
		)
		(fp_line
			(start 0.120396 0.3048)
			(end 0.120396 0.2794)
			(stroke
				(width 0.1)
				(type default)
			)
			(layer "F.Fab")
		)
		(fp_line
			(start -0.12065 0.3048)
			(end -0.67945 0.3048)
			(stroke
				(width 0.1)
				(type default)
			)
			(layer "F.Fab")
		)
		(fp_line
			(start -0.67945 0.3048)
			(end -0.67945 -0.305054)
			(stroke
				(width 0.1)
				(type default)
			)
			(layer "F.Fab")
		)
		(pad "1" smd circle
			(at -0.40005 0 90)
			(size 0 0)
			(layers "F.Cu" "F.Mask" "F.Paste")
			(net "SSD11_AUX_P3V3_EN_R")
		)
		(pad "2" smd circle
			(at 0.40005 0 90)
			(size 0 0)
			(layers "F.Cu" "F.Mask" "F.Paste")
			(net "SSD11_AUX_P3V3_EN")
		)
	)
)
